# S9S_MB_2U (Grand Teton) — schematic netlist excerpt (pin names and nets, part order shuffled) for the footprints in the layout excerpt that follows; sources: Cadence DE-HDL packaged netlist, KiCad conversion of 03242023_DA0F0TMBIJ0_F0T_Motherboard_J_brd_V01_OCP.brd

DB5  TDR_3P  EMPTY  pkg TH2  page 309
  GND  = T1_GND
  IO1  = TDR_SE_40_OHM_IN4
  IO2  = TDR_SE_40_OHM_IN4

R597  Q_RES  0 5% CHIP  pkg 0402LF  page 241 : A = I3C_SPD_DDRABCD_CPU1_BMC_R_SCL ; B = I3C_SPD_DDRABCD_CPU1_BMC_SCL

(kicad_pcb
	(version 20260206)
	(generator "pcbnew")
	(generator_version "10.0")
	(general
		(thickness 1.6)
		(legacy_teardrops no)
	)
	(paper "A4")
	(title_block
		(title "03242023_DA0F0TMBIJ0_F0T_Motherboard_J_brd_V01_OCP.brd")
		(comment 1 "Grand Teton / footprints 5019-5020 of 6105")
	)
	(layers
		(0 "F.Cu" signal "TOP")
		(4 "In1.Cu" signal "GND")
		(6 "In2.Cu" signal "IN1")
		(8 "In3.Cu" signal "GND1")
		(10 "In4.Cu" signal "IN2")
		(12 "In5.Cu" signal "GND2")
		(14 "In6.Cu" signal "IN3")
		(16 "In7.Cu" signal "GND3")
		(18 "In8.Cu" signal "VCC")
		(20 "In9.Cu" signal "VCC1")
		(22 "In10.Cu" signal "GND4")
		(24 "In11.Cu" signal "IN4")
		(26 "In12.Cu" signal "GND5")
		(28 "In13.Cu" signal "IN5")
		(30 "In14.Cu" signal "GND6")
		(32 "In15.Cu" signal "IN6")
		(34 "In16.Cu" signal "GND7")
		(2 "B.Cu" signal "BOTTOM")
		(9 "F.Adhes" user "F.Adhesive")
		(11 "B.Adhes" user "B.Adhesive")
		(13 "F.Paste" user "Package Geometry/Pastemask Top")
		(15 "B.Paste" user "Package Geometry/Pastemask Bottom")
		(5 "F.SilkS" user "Ref Des/Silkscreen Top")
		(7 "B.SilkS" user "Ref Des/Silkscreen Bottom")
		(1 "F.Mask" user "Board Geometry/Soldermask Top")
		(3 "B.Mask" user "Board Geometry/Soldermask Bottom")
		(17 "Dwgs.User" user "User.Drawings")
		(19 "Cmts.User" user "User.Comments")
		(21 "Eco1.User" user "User.Eco1")
		(23 "Eco2.User" user "User.Eco2")
		(25 "Edge.Cuts" user "Board Geometry/Outline")
		(27 "Margin" user)
		(31 "F.CrtYd" user "Package Geometry/Place Bound Top")
		(29 "B.CrtYd" user "Package Geometry/Place Bound Bottom")
		(35 "F.Fab" user "Ref Des/Assembly Top")
		(33 "B.Fab" user "Ref Des/Assembly Bottom")
	)
	(footprint ""
		(layer "B.Cu")
		(at 501.065038 -342.799924)
		(property "Reference" "DB5"
			(at 2.584704 -5.768848 270)
			(unlocked yes)
			(layer "B.SilkS")
			(effects
				(font
					(size 0.7874 0.5842)
					(thickness 0.1524)
				)
				(justify left mirror)
			)
		)
		(property "Value" ""
			(at 0 0 0)
			(layer "B.Fab")
			(effects
				(font
					(size 1.27 1.27)
				)
				(justify mirror)
			)
		)
		(duplicate_pad_numbers_are_jumpers no)
		(fp_line
			(start -3.330702 -4.771136)
			(end 0 4.011168)
			(stroke
				(width 0.1524)
				(type default)
			)
			(layer "B.SilkS")
		)
		(fp_line
			(start 0 4.011168)
			(end 2.826766 -3.442462)
			(stroke
				(width 0.1524)
				(type default)
			)
			(layer "B.SilkS")
		)
		(fp_line
			(start 3.18389 -4.383786)
			(end 3.330702 -4.771136)
			(stroke
				(width 0.1524)
				(type default)
			)
			(layer "B.SilkS")
		)
		(fp_line
			(start 3.330702 -4.771136)
			(end -3.330702 -4.771136)
			(stroke
				(width 0.1524)
				(type default)
			)
			(layer "B.SilkS")
		)
		(fp_line
			(start -3.330702 -4.771136)
			(end 0 4.011168)
			(stroke
				(width 0.1)
				(type default)
			)
			(layer "B.Fab")
		)
		(fp_line
			(start 0 4.011168)
			(end 3.330702 -4.771136)
			(stroke
				(width 0.1)
				(type default)
			)
			(layer "B.Fab")
		)
		(fp_line
			(start 3.330702 -4.771136)
			(end -3.330702 -4.771136)
			(stroke
				(width 0.1)
				(type default)
			)
			(layer "B.Fab")
		)
		(pad "1" thru_hole circle
			(at 0 0 180)
			(size 2.159 2.159)
			(drill 1.7018)
			(layers "*.Cu" "*.Mask")
			(remove_unused_layers no)
			(net "T1_GND")
			(clearance 0.0254)
			(thermal_gap 0.0254)
		)
		(pad "2" thru_hole circle
			(at 1.27 -3.348736 180)
			(size 2.159 2.159)
			(drill 1.7018)
			(layers "*.Cu" "*.Mask")
			(remove_unused_layers no)
			(net "TDR_SE_40_OHM_IN4")
			(clearance 0.0254)
			(thermal_gap 0.0254)
		)
		(pad "3" thru_hole circle
			(at -1.27 -3.348736 180)
			(size 2.159 2.159)
			(drill 1.7018)
			(layers "*.Cu" "*.Mask")
			(remove_unused_layers no)
			(net "TDR_SE_40_OHM_IN4")
			(clearance 0.0254)
			(thermal_gap 0.0254)
		)
	)
	(footprint ""
		(layer "B.Cu")
		(at 186.345068 -13.60043 -90)
		(property "Reference" "R597"
			(at 0 0 90)
			(layer "B.SilkS")
			(hide yes)
			(effects
				(font
					(size 1.27 1.27)
				)
				(justify mirror)
			)
		)
		(property "Value" ""
			(at 0 0 90)
			(layer "B.Fab")
			(effects
				(font
					(size 1.27 1.27)
				)
				(justify mirror)
			)
		)
		(duplicate_pad_numbers_are_jumpers no)
		(fp_line
			(start -0.7874 0.4064)
			(end 0.7874 0.4064)
			(stroke
				(width 0.1524)
				(type default)
			)
			(layer "B.SilkS")
		)
		(fp_line
			(start 0.7874 0.4064)
			(end 0.7874 -0.4064)
			(stroke
				(width 0.1524)
				(type default)
			)
			(layer "B.SilkS")
		)
		(fp_line
			(start -0.7874 -0.4064)
			(end -0.7874 0.4064)
			(stroke
				(width 0.1524)
				(type default)
			)
			(layer "B.SilkS")
		)
		(fp_line
			(start 0.7874 -0.4064)
			(end -0.7874 -0.4064)
			(stroke
				(width 0.1524)
				(type default)
			)
			(layer "B.SilkS")
		)
		(fp_line
			(start -0.67945 0.3048)
			(end -0.120396 0.3048)
			(stroke
				(width 0.1)
				(type default)
			)
			(layer "B.Fab")
		)
		(fp_line
			(start -0.120396 0.3048)
			(end -0.120396 0.2794)
			(stroke
				(width 0.1)
				(type default)
			)
			(layer "B.Fab")
		)
		(fp_line
			(start 0.12065 0.3048)
			(end 0.67945 0.3048)
			(stroke
				(width 0.1)
				(type default)
			)
			(layer "B.Fab")
		)
		(fp_line
			(start 0.67945 0.3048)
			(end 0.67945 -0.305054)
			(stroke
				(width 0.1)
				(type default)
			)
			(layer "B.Fab")
		)
		(fp_line
			(start -0.120396 0.2794)
			(end 0.12065 0.2794)
			(stroke
				(width 0.1)
				(type default)
			)
			(layer "B.Fab")
		)
		(fp_line
			(start 0.12065 0.2794)
			(end 0.12065 0.3048)
			(stroke
				(width 0.1)
				(type default)
			)
			(layer "B.Fab")
		)
		(fp_line
			(start -0.12065 -0.2794)
			(end -0.12065 -0.3048)
			(stroke
				(width 0.1)
				(type default)
			)
			(layer "B.Fab")
		)
		(fp_line
			(start 0.12065 -0.2794)
			(end -0.12065 -0.2794)
			(stroke
				(width 0.1)
				(type default)
			)
			(layer "B.Fab")
		)
		(fp_line
			(start -0.67945 -0.3048)
			(end -0.67945 0.3048)
			(stroke
				(width 0.1)
				(type default)
			)
			(layer "B.Fab")
		)
		(fp_line
			(start -0.12065 -0.3048)
			(end -0.67945 -0.3048)
			(stroke
				(width 0.1)
				(type default)
			)
			(layer "B.Fab")
		)
		(fp_line
			(start 0.12065 -0.305054)
			(end 0.12065 -0.2794)
			(stroke
				(width 0.1)
				(type default)
			)
			(layer "B.Fab")
		)
		(fp_line
			(start 0.67945 -0.305054)
			(end 0.12065 -0.305054)
			(stroke
				(width 0.1)
				(type default)
			)
			(layer "B.Fab")
		)
		(pad "1" smd circle
			(at 0.40005 0 90)
			(size 0 0)
			(layers "B.Cu" "B.Mask" "B.Paste")
			(net "I3C_SPD_DDRABCD_CPU1_BMC_R_SCL")
		)
		(pad "2" smd circle
			(at -0.40005 0 90)
			(size 0 0)
			(layers "B.Cu" "B.Mask" "B.Paste")
			(net "I3C_SPD_DDRABCD_CPU1_BMC_SCL")
		)
	)
)
